# T6G (Grand Teton) — schematic netlist excerpt (pin names and nets, part order shuffled) for the footprints in the layout excerpt that follows; sources: Cadence DE-HDL packaged netlist, KiCad conversion of 04192023_DAF0TMB3IC0_F0TG_MB_C_brd_V02_OCP.brd

R3282  Q_RES  68K 1% EMPTY  pkg 0402LF  page 111 : A = FM_P2E_EQB0 ; B = GND
PC321_SOP1_1  Q_CAP  2.2UF 10V 10% X6S  pkg C0402  page 215 : A = PVDDCR_CPU0_P1_PVCC ; B = GND

(kicad_pcb
	(version 20260206)
	(generator "pcbnew")
	(generator_version "10.0")
	(general
		(thickness 1.6)
		(legacy_teardrops no)
	)
	(paper "A4")
	(title_block
		(title "04192023_DAF0TMB3IC0_F0TG_MB_C_brd_V02_OCP.brd")
		(comment 1 "Grand Teton / footprints 2603-2605 of 8354")
	)
	(layers
		(0 "F.Cu" signal "TOP")
		(4 "In1.Cu" signal "GND")
		(6 "In2.Cu" signal "IN1")
		(8 "In3.Cu" signal "GND1")
		(10 "In4.Cu" signal "IN2")
		(12 "In5.Cu" signal "GND2")
		(14 "In6.Cu" signal "IN3")
		(16 "In7.Cu" signal "GND3")
		(18 "In8.Cu" signal "VCC")
		(20 "In9.Cu" signal "VCC1")
		(22 "In10.Cu" signal "GND4")
		(24 "In11.Cu" signal "IN4")
		(26 "In12.Cu" signal "GND5")
		(28 "In13.Cu" signal "IN5")
		(30 "In14.Cu" signal "GND6")
		(32 "In15.Cu" signal "IN6")
		(34 "In16.Cu" signal "GND7")
		(2 "B.Cu" signal "BOTTOM")
		(9 "F.Adhes" user "F.Adhesive")
		(11 "B.Adhes" user "B.Adhesive")
		(13 "F.Paste" user "Package Geometry/Pastemask Top")
		(15 "B.Paste" user "Package Geometry/Pastemask Bottom")
		(5 "F.SilkS" user "Ref Des/Silkscreen Top")
		(7 "B.SilkS" user "Ref Des/Silkscreen Bottom")
		(1 "F.Mask" user "Board Geometry/Soldermask Top")
		(3 "B.Mask" user "Board Geometry/Soldermask Bottom")
		(17 "Dwgs.User" user "User.Drawings")
		(19 "Cmts.User" user "User.Comments")
		(21 "Eco1.User" user "User.Eco1")
		(23 "Eco2.User" user "User.Eco2")
		(25 "Edge.Cuts" user "Board Geometry/Outline")
		(27 "Margin" user)
		(31 "F.CrtYd" user "Package Geometry/Place Bound Top")
		(29 "B.CrtYd" user "Package Geometry/Place Bound Bottom")
		(35 "F.Fab" user "Ref Des/Assembly Top")
		(33 "B.Fab" user "Ref Des/Assembly Bottom")
	)
	(footprint ""
		(layer "F.Cu")
		(at 26.793444 -426.609256 180)
		(property "Reference" "R3282"
			(at 0 0 180)
			(layer "F.SilkS")
			(hide yes)
			(effects
				(font
					(size 1.27 1.27)
				)
			)
		)
		(property "Value" ""
			(at 0 0 180)
			(layer "F.Fab")
			(effects
				(font
					(size 1.27 1.27)
				)
			)
		)
		(duplicate_pad_numbers_are_jumpers no)
		(fp_line
			(start 0.7874 0.4064)
			(end -0.7874 0.4064)
			(stroke
				(width 0.1524)
				(type default)
			)
			(layer "F.SilkS")
		)
		(fp_line
			(start 0.7874 -0.4064)
			(end 0.7874 0.4064)
			(stroke
				(width 0.1524)
				(type default)
			)
			(layer "F.SilkS")
		)
		(fp_line
			(start -0.7874 0.4064)
			(end -0.7874 -0.4064)
			(stroke
				(width 0.1524)
				(type default)
			)
			(layer "F.SilkS")
		)
		(fp_line
			(start -0.7874 -0.4064)
			(end 0.7874 -0.4064)
			(stroke
				(width 0.1524)
				(type default)
			)
			(layer "F.SilkS")
		)
		(fp_line
			(start 0.67945 0.3048)
			(end 0.120396 0.3048)
			(stroke
				(width 0.1)
				(type default)
			)
			(layer "F.Fab")
		)
		(fp_line
			(start 0.67945 -0.3048)
			(end 0.67945 0.3048)
			(stroke
				(width 0.1)
				(type default)
			)
			(layer "F.Fab")
		)
		(fp_line
			(start 0.12065 -0.2794)
			(end 0.12065 -0.3048)
			(stroke
				(width 0.1)
				(type default)
			)
			(layer "F.Fab")
		)
		(fp_line
			(start 0.12065 -0.3048)
			(end 0.67945 -0.3048)
			(stroke
				(width 0.1)
				(type default)
			)
			(layer "F.Fab")
		)
		(fp_line
			(start 0.120396 0.3048)
			(end 0.120396 0.2794)
			(stroke
				(width 0.1)
				(type default)
			)
			(layer "F.Fab")
		)
		(fp_line
			(start 0.120396 0.2794)
			(end -0.12065 0.2794)
			(stroke
				(width 0.1)
				(type default)
			)
			(layer "F.Fab")
		)
		(fp_line
			(start -0.12065 0.3048)
			(end -0.67945 0.3048)
			(stroke
				(width 0.1)
				(type default)
			)
			(layer "F.Fab")
		)
		(fp_line
			(start -0.12065 0.2794)
			(end -0.12065 0.3048)
			(stroke
				(width 0.1)
				(type default)
			)
			(layer "F.Fab")
		)
		(fp_line
			(start -0.12065 -0.2794)
			(end 0.12065 -0.2794)
			(stroke
				(width 0.1)
				(type default)
			)
			(layer "F.Fab")
		)
		(fp_line
			(start -0.12065 -0.305054)
			(end -0.12065 -0.2794)
			(stroke
				(width 0.1)
				(type default)
			)
			(layer "F.Fab")
		)
		(fp_line
			(start -0.67945 0.3048)
			(end -0.67945 -0.305054)
			(stroke
				(width 0.1)
				(type default)
			)
			(layer "F.Fab")
		)
		(fp_line
			(start -0.67945 -0.305054)
			(end -0.12065 -0.305054)
			(stroke
				(width 0.1)
				(type default)
			)
			(layer "F.Fab")
		)
		(pad "1" smd circle
			(at -0.40005 0 180)
			(size 0 0)
			(layers "F.Cu" "F.Mask" "F.Paste")
			(net "FM_P2E_EQB0")
		)
		(pad "2" smd circle
			(at 0.40005 0 180)
			(size 0 0)
			(layers "F.Cu" "F.Mask" "F.Paste")
			(net "GND")
		)
	)
	(footprint ""
		(layer "F.Cu")
		(at 119.36857 -171.925234 90)
		(property "Reference" "PC321_SOP1_1"
			(at 0 0 90)
			(layer "F.SilkS")
			(hide yes)
			(effects
				(font
					(size 1.27 1.27)
				)
			)
		)
		(property "Value" ""
			(at 0 0 90)
			(layer "F.Fab")
			(effects
				(font
					(size 1.27 1.27)
				)
			)
		)
		(duplicate_pad_numbers_are_jumpers no)
		(fp_line
			(start 0.7874 -0.4064)
			(end 0.7874 0.4064)
			(stroke
				(width 0.1524)
				(type default)
			)
			(layer "F.SilkS")
		)
		(fp_line
			(start -0.7874 -0.4064)
			(end 0.7874 -0.4064)
			(stroke
				(width 0.1524)
				(type default)
			)
			(layer "F.SilkS")
		)
		(fp_line
			(start 0.7874 0.4064)
			(end -0.7874 0.4064)
			(stroke
				(width 0.1524)
				(type default)
			)
			(layer "F.SilkS")
		)
		(fp_line
			(start -0.7874 0.4064)
			(end -0.7874 -0.4064)
			(stroke
				(width 0.1524)
				(type default)
			)
			(layer "F.SilkS")
		)
		(fp_line
			(start -0.12065 -0.305054)
			(end -0.12065 -0.2794)
			(stroke
				(width 0.1)
				(type default)
			)
			(layer "F.Fab")
		)
		(fp_line
			(start -0.67945 -0.305054)
			(end -0.12065 -0.305054)
			(stroke
				(width 0.1)
				(type default)
			)
			(layer "F.Fab")
		)
		(fp_line
			(start 0.67945 -0.3048)
			(end 0.67945 0.3048)
			(stroke
				(width 0.1)
				(type default)
			)
			(layer "F.Fab")
		)
		(fp_line
			(start 0.12065 -0.3048)
			(end 0.67945 -0.3048)
			(stroke
				(width 0.1)
				(type default)
			)
			(layer "F.Fab")
		)
		(fp_line
			(start 0.12065 -0.2794)
			(end 0.12065 -0.3048)
			(stroke
				(width 0.1)
				(type default)
			)
			(layer "F.Fab")
		)
		(fp_line
			(start -0.12065 -0.2794)
			(end 0.12065 -0.2794)
			(stroke
				(width 0.1)
				(type default)
			)
			(layer "F.Fab")
		)
		(fp_line
			(start 0.120396 0.2794)
			(end -0.12065 0.2794)
			(stroke
				(width 0.1)
				(type default)
			)
			(layer "F.Fab")
		)
		(fp_line
			(start -0.12065 0.2794)
			(end -0.12065 0.3048)
			(stroke
				(width 0.1)
				(type default)
			)
			(layer "F.Fab")
		)
		(fp_line
			(start 0.67945 0.3048)
			(end 0.120396 0.3048)
			(stroke
				(width 0.1)
				(type default)
			)
			(layer "F.Fab")
		)
		(fp_line
			(start 0.120396 0.3048)
			(end 0.120396 0.2794)
			(stroke
				(width 0.1)
				(type default)
			)
			(layer "F.Fab")
		)
		(fp_line
			(start -0.12065 0.3048)
			(end -0.67945 0.3048)
			(stroke
				(width 0.1)
				(type default)
			)
			(layer "F.Fab")
		)
		(fp_line
			(start -0.67945 0.3048)
			(end -0.67945 -0.305054)
			(stroke
				(width 0.1)
				(type default)
			)
			(layer "F.Fab")
		)
		(pad "1" smd circle
			(at -0.40005 0 90)
			(size 0 0)
			(layers "F.Cu" "F.Mask" "F.Paste")
			(net "PVDDCR_CPU0_P1_PVCC")
		)
		(pad "2" smd circle
			(at 0.40005 0 90)
			(size 0 0)
			(layers "F.Cu" "F.Mask" "F.Paste")
			(net "GND")
		)
	)
	(footprint ""
		(layer "F.Cu")
		(at 61.0235 -111.940848)
		(property "Reference" "ME12"
			(at 0 0 0)
			(layer "F.SilkS")
			(hide yes)
			(effects
				(font
					(size 1.27 1.27)
				)
			)
		)
		(property "Value" ""
			(at 0 0 0)
			(layer "F.Fab")
			(effects
				(font
					(size 1.27 1.27)
				)
			)
		)
		(duplicate_pad_numbers_are_jumpers no)
		(zone
			(layer "F.Cu")
			(hatch none 0.5)
			(connect_pads
				(clearance 0)
			)
			(min_thickness 0.25)
			(keepout
				(tracks allowed)
				(vias allowed)
				(pads allowed)
				(copperpour allowed)
				(footprints not_allowed)
			)
			(placement
				(enabled no)
				(sheetname "")
			)
			(fill
				(thermal_gap 0.5)
				(thermal_bridge_width 0.5)
				(island_removal_mode 0)
			)
			(polygon
				(pts
					(arc
						(start 71.02348 -111.940848)
						(mid 51.02352 -111.940848)
						(end 71.02348 -111.940848)
					)
				)
			)
		)
	)
)
